# S9S_MB_2U (Grand Teton) — schematic netlist excerpt (pin names and nets, part order shuffled) for the footprints in the layout excerpt that follows; sources: Cadence DE-HDL packaged netlist, KiCad conversion of 03242023_DA0F0TMBIJ0_F0T_Motherboard_J_brd_V01_OCP.brd

PC2202  Q_CAP  100NF 50V 10% X7R  pkg C0402  page 193 : A = P12V_E1S_IMON_0 ; B = GND
R2944  Q_RES  33.2 1% CHIP  pkg 0402LF  page 246 : A = FM_GPU_HSC_EN_BUF_R ; B = FM_GPU_HSC_EN_BUF

(kicad_pcb
	(version 20260206)
	(generator "pcbnew")
	(generator_version "10.0")
	(general
		(thickness 1.6)
		(legacy_teardrops no)
	)
	(paper "A4")
	(title_block
		(title "03242023_DA0F0TMBIJ0_F0T_Motherboard_J_brd_V01_OCP.brd")
		(comment 1 "Grand Teton / footprints 750-751 of 6105")
	)
	(layers
		(0 "F.Cu" signal "TOP")
		(4 "In1.Cu" signal "GND")
		(6 "In2.Cu" signal "IN1")
		(8 "In3.Cu" signal "GND1")
		(10 "In4.Cu" signal "IN2")
		(12 "In5.Cu" signal "GND2")
		(14 "In6.Cu" signal "IN3")
		(16 "In7.Cu" signal "GND3")
		(18 "In8.Cu" signal "VCC")
		(20 "In9.Cu" signal "VCC1")
		(22 "In10.Cu" signal "GND4")
		(24 "In11.Cu" signal "IN4")
		(26 "In12.Cu" signal "GND5")
		(28 "In13.Cu" signal "IN5")
		(30 "In14.Cu" signal "GND6")
		(32 "In15.Cu" signal "IN6")
		(34 "In16.Cu" signal "GND7")
		(2 "B.Cu" signal "BOTTOM")
		(9 "F.Adhes" user "F.Adhesive")
		(11 "B.Adhes" user "B.Adhesive")
		(13 "F.Paste" user "Package Geometry/Pastemask Top")
		(15 "B.Paste" user "Package Geometry/Pastemask Bottom")
		(5 "F.SilkS" user "Ref Des/Silkscreen Top")
		(7 "B.SilkS" user "Ref Des/Silkscreen Bottom")
		(1 "F.Mask" user "Board Geometry/Soldermask Top")
		(3 "B.Mask" user "Board Geometry/Soldermask Bottom")
		(17 "Dwgs.User" user "User.Drawings")
		(19 "Cmts.User" user "User.Comments")
		(21 "Eco1.User" user "User.Eco1")
		(23 "Eco2.User" user "User.Eco2")
		(25 "Edge.Cuts" user "Board Geometry/Outline")
		(27 "Margin" user)
		(31 "F.CrtYd" user "Package Geometry/Place Bound Top")
		(29 "B.CrtYd" user "Package Geometry/Place Bound Bottom")
		(35 "F.Fab" user "Ref Des/Assembly Top")
		(33 "B.Fab" user "Ref Des/Assembly Bottom")
	)
	(footprint ""
		(layer "F.Cu")
		(at 194.020186 -429.41113 -90)
		(property "Reference" "R2944"
			(at 0 0 270)
			(layer "F.SilkS")
			(hide yes)
			(effects
				(font
					(size 1.27 1.27)
				)
			)
		)
		(property "Value" ""
			(at 0 0 270)
			(layer "F.Fab")
			(effects
				(font
					(size 1.27 1.27)
				)
			)
		)
		(duplicate_pad_numbers_are_jumpers no)
		(fp_line
			(start -0.7874 0.4064)
			(end -0.7874 -0.4064)
			(stroke
				(width 0.1524)
				(type default)
			)
			(layer "F.SilkS")
		)
		(fp_line
			(start 0.7874 0.4064)
			(end -0.7874 0.4064)
			(stroke
				(width 0.1524)
				(type default)
			)
			(layer "F.SilkS")
		)
		(fp_line
			(start -0.7874 -0.4064)
			(end 0.7874 -0.4064)
			(stroke
				(width 0.1524)
				(type default)
			)
			(layer "F.SilkS")
		)
		(fp_line
			(start 0.7874 -0.4064)
			(end 0.7874 0.4064)
			(stroke
				(width 0.1524)
				(type default)
			)
			(layer "F.SilkS")
		)
		(fp_line
			(start -0.67945 0.3048)
			(end -0.67945 -0.305054)
			(stroke
				(width 0.1)
				(type default)
			)
			(layer "F.Fab")
		)
		(fp_line
			(start -0.12065 0.3048)
			(end -0.67945 0.3048)
			(stroke
				(width 0.1)
				(type default)
			)
			(layer "F.Fab")
		)
		(fp_line
			(start 0.120396 0.3048)
			(end 0.120396 0.2794)
			(stroke
				(width 0.1)
				(type default)
			)
			(layer "F.Fab")
		)
		(fp_line
			(start 0.67945 0.3048)
			(end 0.120396 0.3048)
			(stroke
				(width 0.1)
				(type default)
			)
			(layer "F.Fab")
		)
		(fp_line
			(start -0.12065 0.2794)
			(end -0.12065 0.3048)
			(stroke
				(width 0.1)
				(type default)
			)
			(layer "F.Fab")
		)
		(fp_line
			(start 0.120396 0.2794)
			(end -0.12065 0.2794)
			(stroke
				(width 0.1)
				(type default)
			)
			(layer "F.Fab")
		)
		(fp_line
			(start -0.12065 -0.2794)
			(end 0.12065 -0.2794)
			(stroke
				(width 0.1)
				(type default)
			)
			(layer "F.Fab")
		)
		(fp_line
			(start 0.12065 -0.2794)
			(end 0.12065 -0.3048)
			(stroke
				(width 0.1)
				(type default)
			)
			(layer "F.Fab")
		)
		(fp_line
			(start 0.12065 -0.3048)
			(end 0.67945 -0.3048)
			(stroke
				(width 0.1)
				(type default)
			)
			(layer "F.Fab")
		)
		(fp_line
			(start 0.67945 -0.3048)
			(end 0.67945 0.3048)
			(stroke
				(width 0.1)
				(type default)
			)
			(layer "F.Fab")
		)
		(fp_line
			(start -0.67945 -0.305054)
			(end -0.12065 -0.305054)
			(stroke
				(width 0.1)
				(type default)
			)
			(layer "F.Fab")
		)
		(fp_line
			(start -0.12065 -0.305054)
			(end -0.12065 -0.2794)
			(stroke
				(width 0.1)
				(type default)
			)
			(layer "F.Fab")
		)
		(pad "1" smd circle
			(at -0.40005 0 270)
			(size 0 0)
			(layers "F.Cu" "F.Mask" "F.Paste")
			(net "FM_GPU_HSC_EN_BUF_R")
		)
		(pad "2" smd circle
			(at 0.40005 0 270)
			(size 0 0)
			(layers "F.Cu" "F.Mask" "F.Paste")
			(net "FM_GPU_HSC_EN_BUF")
		)
	)
	(footprint ""
		(layer "F.Cu")
		(at 257.85953 -53.447442)
		(property "Reference" "PC2202"
			(at 0 0 0)
			(layer "F.SilkS")
			(hide yes)
			(effects
				(font
					(size 1.27 1.27)
				)
			)
		)
		(property "Value" ""
			(at 0 0 0)
			(layer "F.Fab")
			(effects
				(font
					(size 1.27 1.27)
				)
			)
		)
		(duplicate_pad_numbers_are_jumpers no)
		(fp_line
			(start -0.7874 -0.4064)
			(end 0.7874 -0.4064)
			(stroke
				(width 0.1524)
				(type default)
			)
			(layer "F.SilkS")
		)
		(fp_line
			(start -0.7874 0.4064)
			(end -0.7874 -0.4064)
			(stroke
				(width 0.1524)
				(type default)
			)
			(layer "F.SilkS")
		)
		(fp_line
			(start 0.7874 -0.4064)
			(end 0.7874 0.4064)
			(stroke
				(width 0.1524)
				(type default)
			)
			(layer "F.SilkS")
		)
		(fp_line
			(start 0.7874 0.4064)
			(end -0.7874 0.4064)
			(stroke
				(width 0.1524)
				(type default)
			)
			(layer "F.SilkS")
		)
		(fp_line
			(start -0.67945 -0.305054)
			(end -0.12065 -0.305054)
			(stroke
				(width 0.1)
				(type default)
			)
			(layer "F.Fab")
		)
		(fp_line
			(start -0.67945 0.3048)
			(end -0.67945 -0.305054)
			(stroke
				(width 0.1)
				(type default)
			)
			(layer "F.Fab")
		)
		(fp_line
			(start -0.12065 -0.305054)
			(end -0.12065 -0.2794)
			(stroke
				(width 0.1)
				(type default)
			)
			(layer "F.Fab")
		)
		(fp_line
			(start -0.12065 -0.2794)
			(end 0.12065 -0.2794)
			(stroke
				(width 0.1)
				(type default)
			)
			(layer "F.Fab")
		)
		(fp_line
			(start -0.12065 0.2794)
			(end -0.12065 0.3048)
			(stroke
				(width 0.1)
				(type default)
			)
			(layer "F.Fab")
		)
		(fp_line
			(start -0.12065 0.3048)
			(end -0.67945 0.3048)
			(stroke
				(width 0.1)
				(type default)
			)
			(layer "F.Fab")
		)
		(fp_line
			(start 0.120396 0.2794)
			(end -0.12065 0.2794)
			(stroke
				(width 0.1)
				(type default)
			)
			(layer "F.Fab")
		)
		(fp_line
			(start 0.120396 0.3048)
			(end 0.120396 0.2794)
			(stroke
				(width 0.1)
				(type default)
			)
			(layer "F.Fab")
		)
		(fp_line
			(start 0.12065 -0.3048)
			(end 0.67945 -0.3048)
			(stroke
				(width 0.1)
				(type default)
			)
			(layer "F.Fab")
		)
		(fp_line
			(start 0.12065 -0.2794)
			(end 0.12065 -0.3048)
			(stroke
				(width 0.1)
				(type default)
			)
			(layer "F.Fab")
		)
		(fp_line
			(start 0.67945 -0.3048)
			(end 0.67945 0.3048)
			(stroke
				(width 0.1)
				(type default)
			)
			(layer "F.Fab")
		)
		(fp_line
			(start 0.67945 0.3048)
			(end 0.120396 0.3048)
			(stroke
				(width 0.1)
				(type default)
			)
			(layer "F.Fab")
		)
		(pad "1" smd circle
			(at -0.40005 0)
			(size 0 0)
			(layers "F.Cu" "F.Mask" "F.Paste")
			(net "P12V_E1S_IMON_0")
		)
		(pad "2" smd circle
			(at 0.40005 0)
			(size 0 0)
			(layers "F.Cu" "F.Mask" "F.Paste")
			(net "GND")
		)
	)
)
